(kicad_pcb
	(version 20241229)
	(generator "pcbnew")
	(generator_version "9.0")
	(general
		(thickness 1.552)
		(legacy_teardrops no)
	)
	(paper "A4")
	(title_block
		(date "2023-07-25")
		(rev "1.1.4")
		(comment 9 "footprint 195 of 379 (U12), pads 1-87 of 96")
	)
	(layers
		(0 "F.Cu" signal)
		(4 "In1.Cu" signal)
		(6 "In2.Cu" signal)
		(8 "In3.Cu" signal)
		(10 "In4.Cu" signal)
		(12 "In5.Cu" signal)
		(14 "In6.Cu" signal)
		(2 "B.Cu" signal)
		(9 "F.Adhes" user "F.Adhesive")
		(11 "B.Adhes" user "B.Adhesive")
		(13 "F.Paste" user)
		(15 "B.Paste" user)
		(5 "F.SilkS" user "F.Silkscreen")
		(7 "B.SilkS" user "B.Silkscreen")
		(1 "F.Mask" user)
		(3 "B.Mask" user)
		(17 "Dwgs.User" user "User.Drawings")
		(19 "Cmts.User" user "User.Comments")
		(21 "Eco1.User" user "User.Eco1")
		(23 "Eco2.User" user "User.Eco2")
		(25 "Edge.Cuts" user)
		(27 "Margin" user)
		(31 "F.CrtYd" user "F.Courtyard")
		(29 "B.CrtYd" user "B.Courtyard")
		(35 "F.Fab" user)
		(33 "B.Fab" user)
	)
	(footprint "antmicro-footprints:BGA-96-48_8x14mm_Layout16x9_P0.8mm"
		(layer "F.Cu")
		(at 124.26 65.34 180)
		(property "Reference" "U12"
			(at 0 -8.1 180)
			(layer "F.SilkS")
			(effects
				(font
					(size 0.7 0.7)
					(thickness 0.15)
				)
				(justify left bottom)
			)
		)
		(property "Value" "MT41K128M16JT-125_K"
			(at 0 8.4 180)
			(layer "F.Fab")
			(effects
				(font
					(size 0.7 0.7)
					(thickness 0.15)
				)
				(justify left bottom)
			)
		)
		(property "Datasheet" "https://www.mouser.com/datasheet/2/671/mict_s_a0002296722_1-2290882.pdf"
			(at 0 0 180)
			(layer "F.Fab")
			(hide yes)
			(effects
				(font
					(size 1.27 1.27)
					(thickness 0.15)
				)
			)
		)
		(property "Description" "SDRAM - DDR3L Memory IC 2Gbit Parallel 800 MHz 13.75 ns 96-FBGA (8x14)"
			(at 0 0 180)
			(layer "F.Fab")
			(hide yes)
			(effects
				(font
					(size 1.27 1.27)
					(thickness 0.15)
				)
			)
		)
		(property "Author" "Antmicro"
			(at 248.52 130.68 0)
			(layer "F.Fab")
			(hide yes)
			(effects
				(font
					(size 1 1)
					(thickness 0.15)
				)
			)
		)
		(property "License" "Apache-2.0"
			(at 248.52 130.68 0)
			(layer "F.Fab")
			(hide yes)
			(effects
				(font
					(size 1 1)
					(thickness 0.15)
				)
			)
		)
		(property "MPN" "MT41K128M16JT-125:K"
			(at 248.52 130.68 0)
			(layer "F.Fab")
			(hide yes)
			(effects
				(font
					(size 1 1)
					(thickness 0.15)
				)
			)
		)
		(property "Manufacturer" "Micron Technology"
			(at 248.52 130.68 0)
			(layer "F.Fab")
			(hide yes)
			(effects
				(font
					(size 1 1)
					(thickness 0.15)
				)
			)
		)
		(sheetname "/DDR3/")
		(sheetfile "ddr3.kicad_sch")
		(attr smd)
		(pad "A1" smd circle
			(at -3.201 -6 180)
			(size 0.35 0.35)
			(layers "F.Cu" "F.Mask" "F.Paste")
			(net 248 "+1V5")
			(pinfunction "VDDQ")
			(pintype "power_in")
		)
		(pad "A2" smd circle
			(at -2.4 -6 180)
			(size 0.35 0.35)
			(layers "F.Cu" "F.Mask" "F.Paste")
			(net 240 "/DDR3/DDR3_DQ13")
			(pinfunction "DQ13")
			(pintype "bidirectional")
		)
		(pad "A3" smd circle
			(at -1.601 -6 180)
			(size 0.35 0.35)
			(layers "F.Cu" "F.Mask" "F.Paste")
			(net 231 "/DDR3/DDR3_DQ15")
			(pinfunction "DQ15")
			(pintype "bidirectional")
		)
		(pad "A7" smd circle
			(at 1.6 -6 180)
			(size 0.35 0.35)
			(layers "F.Cu" "F.Mask" "F.Paste")
			(net 229 "/DDR3/DDR3_DQ12")
			(pinfunction "DQ12")
			(pintype "bidirectional")
		)
		(pad "A8" smd circle
			(at 2.399 -6 180)
			(size 0.35 0.35)
			(layers "F.Cu" "F.Mask" "F.Paste")
			(net 248 "+1V5")
			(pinfunction "VDDQ")
			(pintype "passive")
		)
		(pad "A9" smd circle
			(at 3.2 -6 180)
			(size 0.35 0.35)
			(layers "F.Cu" "F.Mask" "F.Paste")
			(net 1 "GND")
			(pinfunction "VSS")
			(pintype "passive")
		)
		(pad "B1" smd circle
			(at -3.201 -5.201 180)
			(size 0.35 0.35)
			(layers "F.Cu" "F.Mask" "F.Paste")
			(net 1 "GND")
			(pinfunction "VSSQ")
			(pintype "passive")
		)
		(pad "B2" smd circle
			(at -2.4 -5.201 180)
			(size 0.35 0.35)
			(layers "F.Cu" "F.Mask" "F.Paste")
			(net 248 "+1V5")
			(pinfunction "VDD")
			(pintype "power_in")
		)
		(pad "B3" smd circle
			(at -1.601 -5.201 180)
			(size 0.35 0.35)
			(layers "F.Cu" "F.Mask" "F.Paste")
			(net 1 "GND")
			(pinfunction "VSS")
			(pintype "passive")
		)
		(pad "B7" smd circle
			(at 1.6 -5.201 180)
			(size 0.35 0.35)
			(layers "F.Cu" "F.Mask" "F.Paste")
			(net 239 "/DDR3/DDR3_UDQS_N")
			(pinfunction "~{UDQS}")
			(pintype "bidirectional")
		)
		(pad "B8" smd circle
			(at 2.399 -5.201 180)
			(size 0.35 0.35)
			(layers "F.Cu" "F.Mask" "F.Paste")
			(net 241 "/DDR3/DDR3_DQ14")
			(pinfunction "DQ14")
			(pintype "bidirectional")
		)
		(pad "B9" smd circle
			(at 3.2 -5.201 180)
			(size 0.35 0.35)
			(layers "F.Cu" "F.Mask" "F.Paste")
			(net 1 "GND")
			(pinfunction "VSSQ")
			(pintype "passive")
		)
		(pad "C1" smd circle
			(at -3.201 -4.401 180)
			(size 0.35 0.35)
			(layers "F.Cu" "F.Mask" "F.Paste")
			(net 248 "+1V5")
			(pinfunction "VDDQ")
			(pintype "passive")
		)
		(pad "C2" smd circle
			(at -2.4 -4.401 180)
			(size 0.35 0.35)
			(layers "F.Cu" "F.Mask" "F.Paste")
			(net 228 "/DDR3/DDR3_DQ11")
			(pinfunction "DQ11")
			(pintype "bidirectional")
		)
		(pad "C3" smd circle
			(at -1.601 -4.401 180)
			(size 0.35 0.35)
			(layers "F.Cu" "F.Mask" "F.Paste")
			(net 238 "/DDR3/DDR3_DQ9")
			(pinfunction "DQ9")
			(pintype "bidirectional")
		)
		(pad "C7" smd circle
			(at 1.6 -4.401 180)
			(size 0.35 0.35)
			(layers "F.Cu" "F.Mask" "F.Paste")
			(net 227 "/DDR3/DDR3_UDQS_P")
			(pinfunction "UDQS")
			(pintype "bidirectional")
		)
		(pad "C8" smd circle
			(at 2.399 -4.401 180)
			(size 0.35 0.35)
			(layers "F.Cu" "F.Mask" "F.Paste")
			(net 237 "/DDR3/DDR3_DQ10")
			(pinfunction "DQ10")
			(pintype "bidirectional")
		)
		(pad "C9" smd circle
			(at 3.2 -4.401 180)
			(size 0.35 0.35)
			(layers "F.Cu" "F.Mask" "F.Paste")
			(net 248 "+1V5")
			(pinfunction "VDDQ")
			(pintype "passive")
		)
		(pad "D1" smd circle
			(at -3.201 -3.601 180)
			(size 0.35 0.35)
			(layers "F.Cu" "F.Mask" "F.Paste")
			(net 1 "GND")
			(pinfunction "VSSQ")
			(pintype "passive")
		)
		(pad "D2" smd circle
			(at -2.4 -3.601 180)
			(size 0.35 0.35)
			(layers "F.Cu" "F.Mask" "F.Paste")
			(net 248 "+1V5")
			(pinfunction "VDDQ")
			(pintype "passive")
		)
		(pad "D3" smd circle
			(at -1.601 -3.601 180)
			(size 0.35 0.35)
			(layers "F.Cu" "F.Mask" "F.Paste")
			(net 230 "/DDR3/DDR3_UDM")
			(pinfunction "UDM")
			(pintype "input")
		)
		(pad "D7" smd circle
			(at 1.6 -3.601 180)
			(size 0.35 0.35)
			(layers "F.Cu" "F.Mask" "F.Paste")
			(net 226 "/DDR3/DDR3_DQ8")
			(pinfunction "DQ8")
			(pintype "bidirectional")
		)
		(pad "D8" smd circle
			(at 2.399 -3.601 180)
			(size 0.35 0.35)
			(layers "F.Cu" "F.Mask" "F.Paste")
			(net 1 "GND")
			(pinfunction "VSSQ")
			(pintype "passive")
		)
		(pad "D9" smd circle
			(at 3.2 -3.601 180)
			(size 0.35 0.35)
			(layers "F.Cu" "F.Mask" "F.Paste")
			(net 248 "+1V5")
			(pinfunction "VDD")
			(pintype "passive")
		)
		(pad "E1" smd circle
			(at -3.201 -2.8 180)
			(size 0.35 0.35)
			(layers "F.Cu" "F.Mask" "F.Paste")
			(net 1 "GND")
			(pinfunction "VSS")
			(pintype "passive")
		)
		(pad "E2" smd circle
			(at -2.4 -2.8 180)
			(size 0.35 0.35)
			(layers "F.Cu" "F.Mask" "F.Paste")
			(net 1 "GND")
			(pinfunction "VSSQ")
			(pintype "passive")
		)
		(pad "E3" smd circle
			(at -1.601 -2.8 180)
			(size 0.35 0.35)
			(layers "F.Cu" "F.Mask" "F.Paste")
			(net 221 "/DDR3/DDR3_DQ0")
			(pinfunction "DQ0")
			(pintype "bidirectional")
		)
		(pad "E7" smd circle
			(at 1.6 -2.8 180)
			(size 0.35 0.35)
			(layers "F.Cu" "F.Mask" "F.Paste")
			(net 232 "/DDR3/DDR3_LDM")
			(pinfunction "LDM")
			(pintype "input")
		)
		(pad "E8" smd circle
			(at 2.399 -2.8 180)
			(size 0.35 0.35)
			(layers "F.Cu" "F.Mask" "F.Paste")
			(net 1 "GND")
			(pinfunction "VSSQ")
			(pintype "passive")
		)
		(pad "E9" smd circle
			(at 3.2 -2.8 180)
			(size 0.35 0.35)
			(layers "F.Cu" "F.Mask" "F.Paste")
			(net 248 "+1V5")
			(pinfunction "VDDQ")
			(pintype "passive")
		)
		(pad "F1" smd circle
			(at -3.201 -2 180)
			(size 0.35 0.35)
			(layers "F.Cu" "F.Mask" "F.Paste")
			(net 248 "+1V5")
			(pinfunction "VDDQ")
			(pintype "passive")
		)
		(pad "F2" smd circle
			(at -2.4 -2 180)
			(size 0.35 0.35)
			(layers "F.Cu" "F.Mask" "F.Paste")
			(net 234 "/DDR3/DDR3_DQ2")
			(pinfunction "DQ2")
			(pintype "bidirectional")
		)
		(pad "F3" smd circle
			(at -1.601 -2 180)
			(size 0.35 0.35)
			(layers "F.Cu" "F.Mask" "F.Paste")
			(net 223 "/DDR3/DDR3_LDQS_P")
			(pinfunction "LDQS")
			(pintype "bidirectional")
		)
		(pad "F7" smd circle
			(at 1.6 -2 180)
			(size 0.35 0.35)
			(layers "F.Cu" "F.Mask" "F.Paste")
			(net 233 "/DDR3/DDR3_DQ1")
			(pinfunction "DQ1")
			(pintype "bidirectional")
		)
		(pad "F8" smd circle
			(at 2.399 -2 180)
			(size 0.35 0.35)
			(layers "F.Cu" "F.Mask" "F.Paste")
			(net 222 "/DDR3/DDR3_DQ3")
			(pinfunction "DQ3")
			(pintype "bidirectional")
		)
		(pad "F9" smd circle
			(at 3.2 -2 180)
			(size 0.35 0.35)
			(layers "F.Cu" "F.Mask" "F.Paste")
			(net 1 "GND")
			(pinfunction "VSSQ")
			(pintype "passive")
		)
		(pad "G1" smd circle
			(at -3.201 -1.2 180)
			(size 0.35 0.35)
			(layers "F.Cu" "F.Mask" "F.Paste")
			(net 1 "GND")
			(pinfunction "VSSQ")
			(pintype "passive")
		)
		(pad "G2" smd circle
			(at -2.4 -1.2 180)
			(size 0.35 0.35)
			(layers "F.Cu" "F.Mask" "F.Paste")
			(net 236 "/DDR3/DDR3_DQ6")
			(pinfunction "DQ6")
			(pintype "bidirectional")
		)
		(pad "G3" smd circle
			(at -1.601 -1.2 180)
			(size 0.35 0.35)
			(layers "F.Cu" "F.Mask" "F.Paste")
			(net 220 "/DDR3/DDR3_LDQS_N")
			(pinfunction "~{LDQS}")
			(pintype "bidirectional")
		)
		(pad "G7" smd circle
			(at 1.6 -1.2 180)
			(size 0.35 0.35)
			(layers "F.Cu" "F.Mask" "F.Paste")
			(net 248 "+1V5")
			(pinfunction "VDD")
			(pintype "passive")
		)
		(pad "G8" smd circle
			(at 2.399 -1.2 180)
			(size 0.35 0.35)
			(layers "F.Cu" "F.Mask" "F.Paste")
			(net 1 "GND")
			(pinfunction "VSS")
			(pintype "passive")
		)
		(pad "G9" smd circle
			(at 3.2 -1.2 180)
			(size 0.35 0.35)
			(layers "F.Cu" "F.Mask" "F.Paste")
			(net 1 "GND")
			(pinfunction "VSSQ")
			(pintype "passive")
		)
		(pad "H1" smd circle
			(at -3.201 -0.401 180)
			(size 0.35 0.35)
			(layers "F.Cu" "F.Mask" "F.Paste")
			(net 5 "Vref")
			(pinfunction "VREFDQ")
			(pintype "power_in")
		)
		(pad "H2" smd circle
			(at -2.4 -0.401 180)
			(size 0.35 0.35)
			(layers "F.Cu" "F.Mask" "F.Paste")
			(net 248 "+1V5")
			(pinfunction "VDDQ")
			(pintype "passive")
		)
		(pad "H3" smd circle
			(at -1.601 -0.401 180)
			(size 0.35 0.35)
			(layers "F.Cu" "F.Mask" "F.Paste")
			(net 235 "/DDR3/DDR3_DQ4")
			(pinfunction "DQ4")
			(pintype "bidirectional")
		)
		(pad "H7" smd circle
			(at 1.6 -0.401 180)
			(size 0.35 0.35)
			(layers "F.Cu" "F.Mask" "F.Paste")
			(net 225 "/DDR3/DDR3_DQ7")
			(pinfunction "DQ7")
			(pintype "bidirectional")
		)
		(pad "H8" smd circle
			(at 2.399 -0.401 180)
			(size 0.35 0.35)
			(layers "F.Cu" "F.Mask" "F.Paste")
			(net 224 "/DDR3/DDR3_DQ5")
			(pinfunction "DQ5")
			(pintype "bidirectional")
		)
		(pad "H9" smd circle
			(at 3.2 -0.401 180)
			(size 0.35 0.35)
			(layers "F.Cu" "F.Mask" "F.Paste")
			(net 248 "+1V5")
			(pinfunction "VDDQ")
			(pintype "passive")
		)
		(pad "J1" smd circle
			(at -3.201 0.4 180)
			(size 0.35 0.35)
			(layers "F.Cu" "F.Mask" "F.Paste")
			(net 322 "unconnected-(U12-PadJ1)")
			(pinfunction "J1")
			(pintype "no_connect")
		)
		(pad "J2" smd circle
			(at -2.4 0.4 180)
			(size 0.35 0.35)
			(layers "F.Cu" "F.Mask" "F.Paste")
			(net 1 "GND")
			(pinfunction "VSS")
			(pintype "passive")
		)
		(pad "J3" smd circle
			(at -1.601 0.4 180)
			(size 0.35 0.35)
			(layers "F.Cu" "F.Mask" "F.Paste")
			(net 162 "/DDR3/~{DDR3_RAS}")
			(pinfunction "~{RAS}")
			(pintype "input")
		)
		(pad "J7" smd circle
			(at 1.6 0.4 180)
			(size 0.35 0.35)
			(layers "F.Cu" "F.Mask" "F.Paste")
			(net 143 "/DDR3/DDR3_CK_P")
			(pinfunction "CK")
			(pintype "input")
		)
		(pad "J8" smd circle
			(at 2.399 0.4 180)
			(size 0.35 0.35)
			(layers "F.Cu" "F.Mask" "F.Paste")
			(net 1 "GND")
			(pinfunction "VSS")
			(pintype "passive")
		)
		(pad "J9" smd circle
			(at 3.2 0.4 180)
			(size 0.35 0.35)
			(layers "F.Cu" "F.Mask" "F.Paste")
			(net 318 "unconnected-(U12-PadJ9)")
			(pinfunction "J9")
			(pintype "no_connect")
		)
		(pad "K1" smd circle
			(at -3.201 1.199 180)
			(size 0.35 0.35)
			(layers "F.Cu" "F.Mask" "F.Paste")
			(net 166 "/DDR3/DDR3_ODT")
			(pinfunction "ODT")
			(pintype "input")
		)
		(pad "K2" smd circle
			(at -2.4 1.199 180)
			(size 0.35 0.35)
			(layers "F.Cu" "F.Mask" "F.Paste")
			(net 248 "+1V5")
			(pinfunction "VDD")
			(pintype "passive")
		)
		(pad "K3" smd circle
			(at -1.601 1.199 180)
			(size 0.35 0.35)
			(layers "F.Cu" "F.Mask" "F.Paste")
			(net 161 "/DDR3/~{DDR3_CAS}")
			(pinfunction "~{CAS}")
			(pintype "input")
		)
		(pad "K7" smd circle
			(at 1.6 1.199 180)
			(size 0.35 0.35)
			(layers "F.Cu" "F.Mask" "F.Paste")
			(net 142 "/DDR3/DDR3_CK_N")
			(pinfunction "~{CK}")
			(pintype "input")
		)
		(pad "K8" smd circle
			(at 2.399 1.199 180)
			(size 0.35 0.35)
			(layers "F.Cu" "F.Mask" "F.Paste")
			(net 248 "+1V5")
			(pinfunction "VDD")
			(pintype "passive")
		)
		(pad "K9" smd circle
			(at 3.2 1.199 180)
			(size 0.35 0.35)
			(layers "F.Cu" "F.Mask" "F.Paste")
			(net 165 "/DDR3/DDR3_CKE")
			(pinfunction "CKE")
			(pintype "input")
		)
		(pad "L1" smd circle
			(at -3.201 1.999 180)
			(size 0.35 0.35)
			(layers "F.Cu" "F.Mask" "F.Paste")
			(net 321 "unconnected-(U12-PadL1)")
			(pinfunction "L1")
			(pintype "no_connect")
		)
		(pad "L2" smd circle
			(at -2.4 1.999 180)
			(size 0.35 0.35)
			(layers "F.Cu" "F.Mask" "F.Paste")
			(net 168 "/DDR3/~{DDR3_CS}")
			(pinfunction "~{CS}")
			(pintype "input")
		)
		(pad "L3" smd circle
			(at -1.601 1.999 180)
			(size 0.35 0.35)
			(layers "F.Cu" "F.Mask" "F.Paste")
			(net 163 "/DDR3/~{DDR3_WE}")
			(pinfunction "~{WE}")
			(pintype "input")
		)
		(pad "L7" smd circle
			(at 1.6 1.999 180)
			(size 0.35 0.35)
			(layers "F.Cu" "F.Mask" "F.Paste")
			(net 152 "/DDR3/DDR3_A10")
			(pinfunction "A10/AP")
			(pintype "input")
		)
		(pad "L8" smd circle
			(at 2.399 1.999 180)
			(size 0.35 0.35)
			(layers "F.Cu" "F.Mask" "F.Paste")
			(net 287 "Net-(U12A-ZQ)")
			(pinfunction "ZQ")
			(pintype "passive")
		)
		(pad "L9" smd circle
			(at 3.2 1.999 180)
			(size 0.35 0.35)
			(layers "F.Cu" "F.Mask" "F.Paste")
			(net 317 "unconnected-(U12-PadL9)")
			(pinfunction "L9")
			(pintype "no_connect")
		)
		(pad "M1" smd circle
			(at -3.201 2.799 180)
			(size 0.35 0.35)
			(layers "F.Cu" "F.Mask" "F.Paste")
			(net 1 "GND")
			(pinfunction "VSS")
			(pintype "passive")
		)
		(pad "M2" smd circle
			(at -2.4 2.799 180)
			(size 0.35 0.35)
			(layers "F.Cu" "F.Mask" "F.Paste")
			(net 157 "/DDR3/DDR3_BA0")
			(pinfunction "BA0")
			(pintype "input")
		)
		(pad "M3" smd circle
			(at -1.601 2.799 180)
			(size 0.35 0.35)
			(layers "F.Cu" "F.Mask" "F.Paste")
			(net 167 "/DDR3/DDR3_BA2")
			(pinfunction "BA2")
			(pintype "input")
		)
		(pad "M7" smd circle
			(at 1.6 2.799 180)
			(size 0.35 0.35)
			(layers "F.Cu" "F.Mask" "F.Paste")
			(net 320 "unconnected-(U12-PadM7)")
			(pinfunction "M7")
			(pintype "no_connect")
		)
		(pad "M8" smd circle
			(at 2.399 2.799 180)
			(size 0.35 0.35)
			(layers "F.Cu" "F.Mask" "F.Paste")
			(net 5 "Vref")
			(pinfunction "VREFCA")
			(pintype "power_in")
		)
		(pad "M9" smd circle
			(at 3.2 2.799 180)
			(size 0.35 0.35)
			(layers "F.Cu" "F.Mask" "F.Paste")
			(net 1 "GND")
			(pinfunction "VSS")
			(pintype "passive")
		)
		(pad "N1" smd circle
			(at -3.201 3.6 180)
			(size 0.35 0.35)
			(layers "F.Cu" "F.Mask" "F.Paste")
			(net 248 "+1V5")
			(pinfunction "VDD")
			(pintype "passive")
		)
		(pad "N2" smd circle
			(at -2.4 3.6 180)
			(size 0.35 0.35)
			(layers "F.Cu" "F.Mask" "F.Paste")
			(net 146 "/DDR3/DDR3_A3")
			(pinfunction "A3")
			(pintype "input")
		)
		(pad "N3" smd circle
			(at -1.601 3.6 180)
			(size 0.35 0.35)
			(layers "F.Cu" "F.Mask" "F.Paste")
			(net 147 "/DDR3/DDR3_A0")
			(pinfunction "A0")
			(pintype "input")
		)
		(pad "N7" smd circle
			(at 1.6 3.6 180)
			(size 0.35 0.35)
			(layers "F.Cu" "F.Mask" "F.Paste")
			(net 160 "/DDR3/DDR3_A12")
			(pinfunction "A12/~{BC}")
			(pintype "input")
		)
		(pad "N8" smd circle
			(at 2.399 3.6 180)
			(size 0.35 0.35)
			(layers "F.Cu" "F.Mask" "F.Paste")
			(net 159 "/DDR3/DDR3_BA1")
			(pinfunction "BA1")
			(pintype "input")
		)
		(pad "N9" smd circle
			(at 3.2 3.6 180)
			(size 0.35 0.35)
			(layers "F.Cu" "F.Mask" "F.Paste")
			(net 248 "+1V5")
			(pinfunction "VDD")
			(pintype "passive")
		)
		(pad "P1" smd circle
			(at -3.201 4.4 180)
			(size 0.35 0.35)
			(layers "F.Cu" "F.Mask" "F.Paste")
			(net 1 "GND")
			(pinfunction "VSS")
			(pintype "passive")
		)
		(pad "P2" smd circle
			(at -2.4 4.4 180)
			(size 0.35 0.35)
			(layers "F.Cu" "F.Mask" "F.Paste")
			(net 149 "/DDR3/DDR3_A5")
			(pinfunction "A5")
			(pintype "input")
		)
		(pad "P3" smd circle
			(at -1.601 4.4 180)
			(size 0.35 0.35)
			(layers "F.Cu" "F.Mask" "F.Paste")
			(net 144 "/DDR3/DDR3_A2")
			(pinfunction "A2")
			(pintype "input")
		)
		(pad "P7" smd circle
			(at 1.6 4.4 180)
			(size 0.35 0.35)
			(layers "F.Cu" "F.Mask" "F.Paste")
			(net 145 "/DDR3/DDR3_A1")
			(pinfunction "A1")
			(pintype "input")
		)
		(pad "P8" smd circle
			(at 2.399 4.4 180)
			(size 0.35 0.35)
			(layers "F.Cu" "F.Mask" "F.Paste")
			(net 151 "/DDR3/DDR3_A4")
			(pinfunction "A4")
			(pintype "input")
		)
		(pad "P9" smd circle
			(at 3.2 4.4 180)
			(size 0.35 0.35)
			(layers "F.Cu" "F.Mask" "F.Paste")
			(net 1 "GND")
			(pinfunction "VSS")
			(pintype "passive")
		)
		(pad "R1" smd circle
			(at -3.201 5.2 180)
			(size 0.35 0.35)
			(layers "F.Cu" "F.Mask" "F.Paste")
			(net 248 "+1V5")
			(pinfunction "VDD")
			(pintype "passive")
		)
		(pad "R2" smd circle
			(at -2.4 5.2 180)
			(size 0.35 0.35)
			(layers "F.Cu" "F.Mask" "F.Paste")
			(net 150 "/DDR3/DDR3_A7")
			(pinfunction "A7")
			(pintype "input")
		)
		(pad "R3" smd circle
			(at -1.601 5.2 180)
			(size 0.35 0.35)
			(layers "F.Cu" "F.Mask" "F.Paste")
			(net 153 "/DDR3/DDR3_A9")
			(pinfunction "A9")
			(pintype "input")
		)
	)
)
